(kicad_pcb
	(version 20260206)
	(generator "pcbnew")
	(generator_version "10.0")
	(general
		(thickness 1.6)
		(legacy_teardrops no)
	)
	(paper "A4")
	(title_block
		(title "12092022_DA0F0TMDCD0_F0T_Management_Board_D_brd_V3_OCP.brd")
		(comment 1 "Grand Teton / footprints 142-147 of 1440")
	)
	(layers
		(0 "F.Cu" signal "TOP")
		(4 "In1.Cu" signal "GND")
		(6 "In2.Cu" signal "IN1")
		(8 "In3.Cu" signal "GND1")
		(10 "In4.Cu" signal "IN2")
		(12 "In5.Cu" signal "VCC")
		(14 "In6.Cu" signal "VCC1")
		(16 "In7.Cu" signal "IN3")
		(18 "In8.Cu" signal "GND2")
		(20 "In9.Cu" signal "IN4")
		(22 "In10.Cu" signal "GND3")
		(2 "B.Cu" signal "BOTTOM")
		(9 "F.Adhes" user "F.Adhesive")
		(11 "B.Adhes" user "B.Adhesive")
		(13 "F.Paste" user "Package Geometry/Pastemask Top")
		(15 "B.Paste" user "Package Geometry/Pastemask Bottom")
		(5 "F.SilkS" user "Ref Des/Silkscreen Top")
		(7 "B.SilkS" user "Ref Des/Silkscreen Bottom")
		(1 "F.Mask" user "Board Geometry/Soldermask Top")
		(3 "B.Mask" user "Board Geometry/Soldermask Bottom")
		(17 "Dwgs.User" user "User.Drawings")
		(19 "Cmts.User" user "User.Comments")
		(21 "Eco1.User" user "User.Eco1")
		(23 "Eco2.User" user "User.Eco2")
		(25 "Edge.Cuts" user "Board Geometry/Outline")
		(27 "Margin" user)
		(31 "F.CrtYd" user "Package Geometry/Place Bound Top")
		(29 "B.CrtYd" user "Package Geometry/Place Bound Bottom")
		(35 "F.Fab" user "Ref Des/Assembly Top")
		(33 "B.Fab" user "Ref Des/Assembly Bottom")
	)
	(footprint ""
		(layer "F.Cu")
		(at 103.8225 18.001488 90)
		(property "Reference" "J25"
			(at -6.128512 1.48717 90)
			(unlocked yes)
			(layer "F.SilkS")
			(effects
				(font
					(size 0.7874 0.5842)
					(thickness 0.1524)
				)
				(justify left)
			)
		)
		(property "Value" ""
			(at 0 0 90)
			(layer "F.Fab")
			(effects
				(font
					(size 1.27 1.27)
				)
			)
		)
		(duplicate_pad_numbers_are_jumpers no)
		(fp_line
			(start 1.2192 -2.1082)
			(end 1.2192 -0.458978)
			(stroke
				(width 0.1524)
				(type default)
			)
			(layer "F.SilkS")
		)
		(fp_line
			(start -1.2192 -2.1082)
			(end 1.2192 -2.1082)
			(stroke
				(width 0.1524)
				(type default)
			)
			(layer "F.SilkS")
		)
		(fp_line
			(start 1.2192 0.452882)
			(end 1.2192 2.1082)
			(stroke
				(width 0.1524)
				(type default)
			)
			(layer "F.SilkS")
		)
		(fp_line
			(start 1.2192 2.1082)
			(end -1.2192 2.1082)
			(stroke
				(width 0.1524)
				(type default)
			)
			(layer "F.SilkS")
		)
		(fp_line
			(start -1.2192 2.1082)
			(end -1.2192 -2.1082)
			(stroke
				(width 0.1524)
				(type default)
			)
			(layer "F.SilkS")
		)
		(pad "" np_thru_hole circle
			(at -2.8829 -1.27)
			(size 1.0414 1.0414)
			(drill 1.0414)
			(layers "*.Cu" "*.Mask")
			(clearance 0.381)
			(thermal_gap 0.381)
		)
		(pad "" np_thru_hole circle
			(at -2.8829 1.27)
			(size 1.0414 1.0414)
			(drill 1.0414)
			(layers "*.Cu" "*.Mask")
			(clearance 0.381)
			(thermal_gap 0.381)
		)
		(pad "" np_thru_hole circle
			(at 3.4671 -1.27)
			(size 1.0414 1.0414)
			(drill 1.0414)
			(layers "*.Cu" "*.Mask")
			(clearance 0.381)
			(thermal_gap 0.381)
		)
		(pad "" np_thru_hole circle
			(at 3.4671 1.27)
			(size 1.0414 1.0414)
			(drill 1.0414)
			(layers "*.Cu" "*.Mask")
			(clearance 0.381)
			(thermal_gap 0.381)
		)
		(pad "1" smd rect
			(at 0.8255 -0.249936)
			(size 0.3048 0.508)
			(layers "F.Cu" "F.Mask" "F.Paste")
			(net "85_10INCH_TOP_DN")
		)
		(pad "2" smd rect
			(at 0.8255 0.249936)
			(size 0.3048 0.508)
			(layers "F.Cu" "F.Mask" "F.Paste")
			(net "85_10INCH_TOP_DP")
		)
		(pad "3" smd circle
			(at 0 0 90)
			(size 0 0)
			(layers "F.Cu" "F.Mask" "F.Paste")
			(net "GND_P1")
		)
		(zone
			(layer "F.Cu")
			(hatch none 0.5)
			(connect_pads
				(clearance 0)
			)
			(min_thickness 0.25)
			(keepout
				(tracks not_allowed)
				(vias allowed)
				(pads allowed)
				(copperpour not_allowed)
				(footprints allowed)
			)
			(placement
				(enabled no)
				(sheetname "")
			)
			(fill
				(thermal_gap 0.5)
				(thermal_bridge_width 0.5)
				(island_removal_mode 0)
			)
			(polygon
				(pts
					(xy 103.27386 16.883888) (xy 103.369364 16.883888) (xy 103.369364 17.480788) (xy 103.775764 17.480788)
					(xy 103.775764 16.883888) (xy 103.869236 16.883888) (xy 103.869236 17.480788) (xy 104.275636 17.480788)
					(xy 104.275636 16.883888) (xy 104.37114 16.883888) (xy 104.37114 17.582388) (xy 103.27386 17.582388)
				)
			)
		)
		(zone
			(layers "F.Cu" "B.Cu" "In1.Cu" "In2.Cu" "In3.Cu" "In4.Cu" "In5.Cu" "In6.Cu"
				"In7.Cu" "In8.Cu" "In9.Cu" "In10.Cu"
			)
			(hatch none 0.5)
			(connect_pads
				(clearance 0)
			)
			(min_thickness 0.25)
			(keepout
				(tracks not_allowed)
				(vias allowed)
				(pads allowed)
				(copperpour not_allowed)
				(footprints allowed)
			)
			(placement
				(enabled no)
				(sheetname "")
			)
			(fill
				(thermal_gap 0.5)
				(thermal_bridge_width 0.5)
				(island_removal_mode 0)
			)
			(polygon
				(pts
					(arc
						(start 103.4796 14.534388)
						(mid 101.6254 14.534388)
						(end 103.4796 14.534388)
					)
				)
			)
		)
		(zone
			(layers "F.Cu" "B.Cu" "In1.Cu" "In2.Cu" "In3.Cu" "In4.Cu" "In5.Cu" "In6.Cu"
				"In7.Cu" "In8.Cu" "In9.Cu" "In10.Cu"
			)
			(hatch none 0.5)
			(connect_pads
				(clearance 0)
			)
			(min_thickness 0.25)
			(keepout
				(tracks not_allowed)
				(vias allowed)
				(pads allowed)
				(copperpour not_allowed)
				(footprints allowed)
			)
			(placement
				(enabled no)
				(sheetname "")
			)
			(fill
				(thermal_gap 0.5)
				(thermal_bridge_width 0.5)
				(island_removal_mode 0)
			)
			(polygon
				(pts
					(arc
						(start 103.4796 20.884388)
						(mid 101.6254 20.884388)
						(end 103.4796 20.884388)
					)
				)
			)
		)
		(zone
			(layers "F.Cu" "B.Cu" "In1.Cu" "In2.Cu" "In3.Cu" "In4.Cu" "In5.Cu" "In6.Cu"
				"In7.Cu" "In8.Cu" "In9.Cu" "In10.Cu"
			)
			(hatch none 0.5)
			(connect_pads
				(clearance 0)
			)
			(min_thickness 0.25)
			(keepout
				(tracks not_allowed)
				(vias allowed)
				(pads allowed)
				(copperpour not_allowed)
				(footprints allowed)
			)
			(placement
				(enabled no)
				(sheetname "")
			)
			(fill
				(thermal_gap 0.5)
				(thermal_bridge_width 0.5)
				(island_removal_mode 0)
			)
			(polygon
				(pts
					(arc
						(start 106.0196 14.534388)
						(mid 104.1654 14.534388)
						(end 106.0196 14.534388)
					)
				)
			)
		)
		(zone
			(layers "F.Cu" "B.Cu" "In1.Cu" "In2.Cu" "In3.Cu" "In4.Cu" "In5.Cu" "In6.Cu"
				"In7.Cu" "In8.Cu" "In9.Cu" "In10.Cu"
			)
			(hatch none 0.5)
			(connect_pads
				(clearance 0)
			)
			(min_thickness 0.25)
			(keepout
				(tracks not_allowed)
				(vias allowed)
				(pads allowed)
				(copperpour not_allowed)
				(footprints allowed)
			)
			(placement
				(enabled no)
				(sheetname "")
			)
			(fill
				(thermal_gap 0.5)
				(thermal_bridge_width 0.5)
				(island_removal_mode 0)
			)
			(polygon
				(pts
					(arc
						(start 106.0196 20.884388)
						(mid 104.1654 20.884388)
						(end 106.0196 20.884388)
					)
				)
			)
		)
	)
	(footprint ""
		(layer "F.Cu")
		(at 85.2932 -16.764)
		(property "Reference" "R733"
			(at 0 0 0)
			(layer "F.SilkS")
			(hide yes)
			(effects
				(font
					(size 1.27 1.27)
				)
			)
		)
		(property "Value" ""
			(at 0 0 0)
			(layer "F.Fab")
			(effects
				(font
					(size 1.27 1.27)
				)
			)
		)
		(duplicate_pad_numbers_are_jumpers no)
		(fp_line
			(start -0.7874 -0.4064)
			(end 0.7874 -0.4064)
			(stroke
				(width 0.1524)
				(type default)
			)
			(layer "F.SilkS")
		)
		(fp_line
			(start -0.7874 0.4064)
			(end -0.7874 -0.4064)
			(stroke
				(width 0.1524)
				(type default)
			)
			(layer "F.SilkS")
		)
		(fp_line
			(start 0.7874 -0.4064)
			(end 0.7874 0.4064)
			(stroke
				(width 0.1524)
				(type default)
			)
			(layer "F.SilkS")
		)
		(fp_line
			(start 0.7874 0.4064)
			(end -0.7874 0.4064)
			(stroke
				(width 0.1524)
				(type default)
			)
			(layer "F.SilkS")
		)
		(fp_line
			(start -0.67945 -0.305054)
			(end -0.12065 -0.305054)
			(stroke
				(width 0.1)
				(type default)
			)
			(layer "F.Fab")
		)
		(fp_line
			(start -0.67945 0.3048)
			(end -0.67945 -0.305054)
			(stroke
				(width 0.1)
				(type default)
			)
			(layer "F.Fab")
		)
		(fp_line
			(start -0.12065 -0.305054)
			(end -0.12065 -0.2794)
			(stroke
				(width 0.1)
				(type default)
			)
			(layer "F.Fab")
		)
		(fp_line
			(start -0.12065 -0.2794)
			(end 0.12065 -0.2794)
			(stroke
				(width 0.1)
				(type default)
			)
			(layer "F.Fab")
		)
		(fp_line
			(start -0.12065 0.2794)
			(end -0.12065 0.3048)
			(stroke
				(width 0.1)
				(type default)
			)
			(layer "F.Fab")
		)
		(fp_line
			(start -0.12065 0.3048)
			(end -0.67945 0.3048)
			(stroke
				(width 0.1)
				(type default)
			)
			(layer "F.Fab")
		)
		(fp_line
			(start 0.120396 0.2794)
			(end -0.12065 0.2794)
			(stroke
				(width 0.1)
				(type default)
			)
			(layer "F.Fab")
		)
		(fp_line
			(start 0.120396 0.3048)
			(end 0.120396 0.2794)
			(stroke
				(width 0.1)
				(type default)
			)
			(layer "F.Fab")
		)
		(fp_line
			(start 0.12065 -0.3048)
			(end 0.67945 -0.3048)
			(stroke
				(width 0.1)
				(type default)
			)
			(layer "F.Fab")
		)
		(fp_line
			(start 0.12065 -0.2794)
			(end 0.12065 -0.3048)
			(stroke
				(width 0.1)
				(type default)
			)
			(layer "F.Fab")
		)
		(fp_line
			(start 0.67945 -0.3048)
			(end 0.67945 0.3048)
			(stroke
				(width 0.1)
				(type default)
			)
			(layer "F.Fab")
		)
		(fp_line
			(start 0.67945 0.3048)
			(end 0.120396 0.3048)
			(stroke
				(width 0.1)
				(type default)
			)
			(layer "F.Fab")
		)
		(pad "1" smd circle
			(at -0.40005 0)
			(size 0 0)
			(layers "F.Cu" "F.Mask" "F.Paste")
			(net "REAR_ID_RST_BTN_N")
		)
		(pad "2" smd circle
			(at 0.40005 0)
			(size 0 0)
			(layers "F.Cu" "F.Mask" "F.Paste")
			(net "FM_DEBUG_RST_BTN_N")
		)
	)
	(footprint ""
		(layer "F.Cu")
		(at 47.752 -81.1276 90)
		(property "Reference" "R592"
			(at 0 0 90)
			(layer "F.SilkS")
			(hide yes)
			(effects
				(font
					(size 1.27 1.27)
				)
			)
		)
		(property "Value" ""
			(at 0 0 90)
			(layer "F.Fab")
			(effects
				(font
					(size 1.27 1.27)
				)
			)
		)
		(duplicate_pad_numbers_are_jumpers no)
		(fp_line
			(start 0.7874 -0.4064)
			(end 0.7874 0.4064)
			(stroke
				(width 0.1524)
				(type default)
			)
			(layer "F.SilkS")
		)
		(fp_line
			(start -0.7874 -0.4064)
			(end 0.7874 -0.4064)
			(stroke
				(width 0.1524)
				(type default)
			)
			(layer "F.SilkS")
		)
		(fp_line
			(start 0.7874 0.4064)
			(end -0.7874 0.4064)
			(stroke
				(width 0.1524)
				(type default)
			)
			(layer "F.SilkS")
		)
		(fp_line
			(start -0.7874 0.4064)
			(end -0.7874 -0.4064)
			(stroke
				(width 0.1524)
				(type default)
			)
			(layer "F.SilkS")
		)
		(fp_line
			(start -0.12065 -0.305054)
			(end -0.12065 -0.2794)
			(stroke
				(width 0.1)
				(type default)
			)
			(layer "F.Fab")
		)
		(fp_line
			(start -0.67945 -0.305054)
			(end -0.12065 -0.305054)
			(stroke
				(width 0.1)
				(type default)
			)
			(layer "F.Fab")
		)
		(fp_line
			(start 0.67945 -0.3048)
			(end 0.67945 0.3048)
			(stroke
				(width 0.1)
				(type default)
			)
			(layer "F.Fab")
		)
		(fp_line
			(start 0.12065 -0.3048)
			(end 0.67945 -0.3048)
			(stroke
				(width 0.1)
				(type default)
			)
			(layer "F.Fab")
		)
		(fp_line
			(start 0.12065 -0.2794)
			(end 0.12065 -0.3048)
			(stroke
				(width 0.1)
				(type default)
			)
			(layer "F.Fab")
		)
		(fp_line
			(start -0.12065 -0.2794)
			(end 0.12065 -0.2794)
			(stroke
				(width 0.1)
				(type default)
			)
			(layer "F.Fab")
		)
		(fp_line
			(start 0.120396 0.2794)
			(end -0.12065 0.2794)
			(stroke
				(width 0.1)
				(type default)
			)
			(layer "F.Fab")
		)
		(fp_line
			(start -0.12065 0.2794)
			(end -0.12065 0.3048)
			(stroke
				(width 0.1)
				(type default)
			)
			(layer "F.Fab")
		)
		(fp_line
			(start 0.67945 0.3048)
			(end 0.120396 0.3048)
			(stroke
				(width 0.1)
				(type default)
			)
			(layer "F.Fab")
		)
		(fp_line
			(start 0.120396 0.3048)
			(end 0.120396 0.2794)
			(stroke
				(width 0.1)
				(type default)
			)
			(layer "F.Fab")
		)
		(fp_line
			(start -0.12065 0.3048)
			(end -0.67945 0.3048)
			(stroke
				(width 0.1)
				(type default)
			)
			(layer "F.Fab")
		)
		(fp_line
			(start -0.67945 0.3048)
			(end -0.67945 -0.305054)
			(stroke
				(width 0.1)
				(type default)
			)
			(layer "F.Fab")
		)
		(pad "1" smd circle
			(at -0.40005 0 90)
			(size 0 0)
			(layers "F.Cu" "F.Mask" "F.Paste")
			(net "P3V3_AUX")
		)
		(pad "2" smd circle
			(at 0.40005 0 90)
			(size 0 0)
			(layers "F.Cu" "F.Mask" "F.Paste")
			(net "PU_J1_P1")
		)
	)
	(footprint ""
		(layer "F.Cu")
		(at 9.1694 -104.6226)
		(property "Reference" "C217"
			(at 0 0 0)
			(layer "F.SilkS")
			(hide yes)
			(effects
				(font
					(size 1.27 1.27)
				)
			)
		)
		(property "Value" ""
			(at 0 0 0)
			(layer "F.Fab")
			(effects
				(font
					(size 1.27 1.27)
				)
			)
		)
		(duplicate_pad_numbers_are_jumpers no)
		(fp_line
			(start -0.7874 -0.4064)
			(end 0.7874 -0.4064)
			(stroke
				(width 0.1524)
				(type default)
			)
			(layer "F.SilkS")
		)
		(fp_line
			(start -0.7874 0.4064)
			(end -0.7874 -0.4064)
			(stroke
				(width 0.1524)
				(type default)
			)
			(layer "F.SilkS")
		)
		(fp_line
			(start 0.7874 -0.4064)
			(end 0.7874 0.4064)
			(stroke
				(width 0.1524)
				(type default)
			)
			(layer "F.SilkS")
		)
		(fp_line
			(start 0.7874 0.4064)
			(end -0.7874 0.4064)
			(stroke
				(width 0.1524)
				(type default)
			)
			(layer "F.SilkS")
		)
		(fp_line
			(start -0.67945 -0.305054)
			(end -0.12065 -0.305054)
			(stroke
				(width 0.1)
				(type default)
			)
			(layer "F.Fab")
		)
		(fp_line
			(start -0.67945 0.3048)
			(end -0.67945 -0.305054)
			(stroke
				(width 0.1)
				(type default)
			)
			(layer "F.Fab")
		)
		(fp_line
			(start -0.12065 -0.305054)
			(end -0.12065 -0.2794)
			(stroke
				(width 0.1)
				(type default)
			)
			(layer "F.Fab")
		)
		(fp_line
			(start -0.12065 -0.2794)
			(end 0.12065 -0.2794)
			(stroke
				(width 0.1)
				(type default)
			)
			(layer "F.Fab")
		)
		(fp_line
			(start -0.12065 0.2794)
			(end -0.12065 0.3048)
			(stroke
				(width 0.1)
				(type default)
			)
			(layer "F.Fab")
		)
		(fp_line
			(start -0.12065 0.3048)
			(end -0.67945 0.3048)
			(stroke
				(width 0.1)
				(type default)
			)
			(layer "F.Fab")
		)
		(fp_line
			(start 0.120396 0.2794)
			(end -0.12065 0.2794)
			(stroke
				(width 0.1)
				(type default)
			)
			(layer "F.Fab")
		)
		(fp_line
			(start 0.120396 0.3048)
			(end 0.120396 0.2794)
			(stroke
				(width 0.1)
				(type default)
			)
			(layer "F.Fab")
		)
		(fp_line
			(start 0.12065 -0.3048)
			(end 0.67945 -0.3048)
			(stroke
				(width 0.1)
				(type default)
			)
			(layer "F.Fab")
		)
		(fp_line
			(start 0.12065 -0.2794)
			(end 0.12065 -0.3048)
			(stroke
				(width 0.1)
				(type default)
			)
			(layer "F.Fab")
		)
		(fp_line
			(start 0.67945 -0.3048)
			(end 0.67945 0.3048)
			(stroke
				(width 0.1)
				(type default)
			)
			(layer "F.Fab")
		)
		(fp_line
			(start 0.67945 0.3048)
			(end 0.120396 0.3048)
			(stroke
				(width 0.1)
				(type default)
			)
			(layer "F.Fab")
		)
		(pad "1" smd circle
			(at -0.40005 0)
			(size 0 0)
			(layers "F.Cu" "F.Mask" "F.Paste")
			(net "J7_P1")
		)
		(pad "2" smd circle
			(at 0.40005 0)
			(size 0 0)
			(layers "F.Cu" "F.Mask" "F.Paste")
			(net "GND")
		)
	)
	(footprint ""
		(layer "F.Cu")
		(at 6.096 -53.594 180)
		(property "Reference" "PC207"
			(at 0 0 180)
			(layer "F.SilkS")
			(hide yes)
			(effects
				(font
					(size 1.27 1.27)
				)
			)
		)
		(property "Value" ""
			(at 0 0 180)
			(layer "F.Fab")
			(effects
				(font
					(size 1.27 1.27)
				)
			)
		)
		(duplicate_pad_numbers_are_jumpers no)
		(fp_line
			(start 1.524 0.762)
			(end -1.524 0.762)
			(stroke
				(width 0.1524)
				(type default)
			)
			(layer "F.SilkS")
		)
		(fp_line
			(start 1.524 -0.762)
			(end 1.524 0.762)
			(stroke
				(width 0.1524)
				(type default)
			)
			(layer "F.SilkS")
		)
		(fp_line
			(start -1.524 0.762)
			(end -1.524 -0.762)
			(stroke
				(width 0.1524)
				(type default)
			)
			(layer "F.SilkS")
		)
		(fp_line
			(start -1.524 -0.762)
			(end 1.524 -0.762)
			(stroke
				(width 0.1524)
				(type default)
			)
			(layer "F.SilkS")
		)
		(fp_line
			(start 1.1049 0.724916)
			(end 1.1049 -0.724916)
			(stroke
				(width 0.1)
				(type default)
			)
			(layer "F.Fab")
		)
		(fp_line
			(start 1.1049 -0.724916)
			(end -1.1049 -0.724916)
			(stroke
				(width 0.1)
				(type default)
			)
			(layer "F.Fab")
		)
		(fp_line
			(start -1.1049 0.724916)
			(end 1.1049 0.724916)
			(stroke
				(width 0.1)
				(type default)
			)
			(layer "F.Fab")
		)
		(fp_line
			(start -1.1049 -0.724916)
			(end -1.1049 0.724916)
			(stroke
				(width 0.1)
				(type default)
			)
			(layer "F.Fab")
		)
		(pad "1" smd rect
			(at -0.889 0)
			(size 1.016 1.27)
			(layers "F.Cu" "F.Mask" "F.Paste")
			(net "SW_P5V_AUX_FLT")
		)
		(pad "2" smd rect
			(at 0.889 0)
			(size 1.016 1.27)
			(layers "F.Cu" "F.Mask" "F.Paste")
			(net "GND")
		)
	)
	(footprint ""
		(layer "F.Cu")
		(at -4.251198 -136.217152)
		(property "Reference" "DM1"
			(at -0.3937 -0.588518 0)
			(unlocked yes)
			(layer "F.SilkS")
			(effects
				(font
					(size 0.254 0.127)
					(thickness 0.000001)
				)
				(justify left)
			)
		)
		(property "Value" ""
			(at 0 0 0)
			(layer "F.Fab")
			(effects
				(font
					(size 1.27 1.27)
				)
			)
		)
		(duplicate_pad_numbers_are_jumpers no)
		(pad "1" smd circle
			(at 0 0)
			(size 0.762 0.762)
			(layers "F.Cu" "F.Mask" "F.Paste")
			(net "Net_28")
		)
	)
)
